(kicad_pcb
	(version 20260206)
	(generator "pcbnew")
	(generator_version "10.0")
	(general
		(thickness 1.6)
		(legacy_teardrops no)
	)
	(paper "A4")
	(title_block
		(title "Bryce Canyon_R.DPB_16317-1_OCP.brd")
		(comment 1 "Bryce Canyon / footprints 1007-1014 of 2099")
	)
	(layers
		(0 "F.Cu" signal "TOP")
		(4 "In1.Cu" signal "L2GND")
		(6 "In2.Cu" signal "L3")
		(8 "In3.Cu" signal "L4VCC")
		(10 "In4.Cu" signal "L5VCC")
		(12 "In5.Cu" signal "L6")
		(14 "In6.Cu" signal "L7GND")
		(2 "B.Cu" signal "BOTTOM")
		(9 "F.Adhes" user "F.Adhesive")
		(11 "B.Adhes" user "B.Adhesive")
		(13 "F.Paste" user "Package Geometry/Pastemask Top")
		(15 "B.Paste" user "Package Geometry/Pastemask Bottom")
		(5 "F.SilkS" user "Ref Des/Silkscreen Top")
		(7 "B.SilkS" user "Ref Des/Silkscreen Bottom")
		(1 "F.Mask" user "Board Geometry/Soldermask Top")
		(3 "B.Mask" user "Board Geometry/Soldermask Bottom")
		(17 "Dwgs.User" user "User.Drawings")
		(19 "Cmts.User" user "User.Comments")
		(21 "Eco1.User" user "User.Eco1")
		(23 "Eco2.User" user "User.Eco2")
		(25 "Edge.Cuts" user "Board Geometry/Outline")
		(27 "Margin" user)
		(31 "F.CrtYd" user "Package Geometry/Place Bound Top")
		(29 "B.CrtYd" user "Package Geometry/Place Bound Bottom")
		(35 "F.Fab" user "Ref Des/Assembly Top")
		(33 "B.Fab" user "Ref Des/Assembly Bottom")
	)
	(footprint ""
		(layer "F.Cu")
		(at 384.734562 -129.66065 -90)
		(property "Reference" "C289"
			(at 0 0 270)
			(layer "F.SilkS")
			(hide yes)
			(effects
				(font
					(size 1.27 1.27)
				)
			)
		)
		(property "Value" "SCD01U16V1KX-GP"
			(at -2.8321 -1.7399 270)
			(unlocked yes)
			(layer "F.Fab")
			(hide yes)
			(effects
				(font
					(size 1.016 1.016)
					(thickness 0.1524)
				)
			)
		)
		(property "Device Type" "C0201H13"
			(at -2.8321 -3.2639 270)
			(unlocked yes)
			(layer "F.Fab")
			(hide yes)
			(effects
				(font
					(size 1.016 1.016)
					(thickness 0.1524)
				)
			)
		)
		(duplicate_pad_numbers_are_jumpers no)
		(fp_rect
			(start -0.2794 0.6477)
			(end 0.2794 -0.6477)
			(stroke
				(width 0)
				(type default)
			)
			(fill no)
			(layer "F.CrtYd")
		)
		(fp_rect
			(start -0.2794 0.6477)
			(end 0.2794 -0.6477)
			(stroke
				(width 0)
				(type default)
			)
			(fill no)
			(layer "F.Fab")
		)
		(pad "1" smd custom
			(at 0 -0.2794 270)
			(size 0.0762 0.0762)
			(layers "F.Cu" "F.Mask" "F.Paste")
			(net "SAS_HDD_RX_P20")
			(options
				(clearance outline)
				(anchor circle)
			)
			(primitives
				(gr_poly
					(pts
						(arc
							(start 0.1524 -0.127)
							(mid 0.137521 -0.162921)
							(end 0.1016 -0.1778)
						)
						(arc
							(start -0.1016 -0.1778)
							(mid -0.137521 -0.162921)
							(end -0.1524 -0.127)
						)
						(arc
							(start -0.1524 0.127)
							(mid -0.137521 0.162921)
							(end -0.1016 0.1778)
						)
						(arc
							(start 0.1016 0.1778)
							(mid 0.137521 0.162921)
							(end 0.1524 0.127)
						)
					)
					(width 0)
					(fill yes)
				)
			)
		)
		(pad "2" smd custom
			(at 0 0.2794 270)
			(size 0.0762 0.0762)
			(layers "F.Cu" "F.Mask" "F.Paste")
			(net "PHY_SCC_B_TO_DRV_B_20_DP")
			(options
				(clearance outline)
				(anchor circle)
			)
			(primitives
				(gr_poly
					(pts
						(arc
							(start 0.1524 -0.127)
							(mid 0.137521 -0.162921)
							(end 0.1016 -0.1778)
						)
						(arc
							(start -0.1016 -0.1778)
							(mid -0.137521 -0.162921)
							(end -0.1524 -0.127)
						)
						(arc
							(start -0.1524 0.127)
							(mid -0.137521 0.162921)
							(end -0.1016 0.1778)
						)
						(arc
							(start 0.1016 0.1778)
							(mid 0.137521 0.162921)
							(end 0.1524 0.127)
						)
					)
					(width 0)
					(fill yes)
				)
			)
		)
	)
	(footprint ""
		(layer "F.Cu")
		(at 439.036714 -119.646446 90)
		(property "Reference" "R1165"
			(at 0 0 90)
			(layer "F.SilkS")
			(hide yes)
			(effects
				(font
					(size 1.27 1.27)
				)
			)
		)
		(property "Value" "100KR2F-L1-GP"
			(at 0.064008 -3.993896 90)
			(unlocked yes)
			(layer "F.Fab")
			(hide yes)
			(effects
				(font
					(size 1.016 1.016)
					(thickness 0.1524)
				)
			)
		)
		(property "Device Type" "R402H16"
			(at 0.064008 -5.517896 90)
			(unlocked yes)
			(layer "F.Fab")
			(hide yes)
			(effects
				(font
					(size 1.016 1.016)
					(thickness 0.1524)
				)
			)
		)
		(duplicate_pad_numbers_are_jumpers no)
		(fp_line
			(start 0.508 -0.9398)
			(end -0.508 -0.9398)
			(stroke
				(width 0.1524)
				(type default)
			)
			(layer "F.SilkS")
		)
		(fp_line
			(start -0.508 -0.9398)
			(end -0.508 0.9398)
			(stroke
				(width 0.1524)
				(type default)
			)
			(layer "F.SilkS")
		)
		(fp_rect
			(start -0.508 0.9398)
			(end 0.508 -0.9398)
			(stroke
				(width 0)
				(type default)
			)
			(fill no)
			(layer "F.CrtYd")
		)
		(fp_rect
			(start -0.508 0.9398)
			(end 0.508 -0.9398)
			(stroke
				(width 0)
				(type default)
			)
			(fill no)
			(layer "F.Fab")
		)
		(pad "1" smd custom
			(at 0 -0.4445 90)
			(size 0.1397 0.1397)
			(layers "F.Cu" "F.Mask" "F.Paste")
			(net "AGND_P5V_B_4")
			(options
				(clearance outline)
				(anchor circle)
			)
			(primitives
				(gr_poly
					(pts
						(arc
							(start -0.1778 -0.2794)
							(mid -0.249642 -0.249642)
							(end -0.2794 -0.1778)
						)
						(arc
							(start -0.2794 0.1778)
							(mid -0.249642 0.249642)
							(end -0.1778 0.2794)
						)
						(arc
							(start 0.1778 0.2794)
							(mid 0.249642 0.249642)
							(end 0.2794 0.1778)
						)
						(arc
							(start 0.2794 -0.1778)
							(mid 0.249642 -0.249642)
							(end 0.1778 -0.2794)
						)
					)
					(width 0)
					(fill yes)
				)
			)
		)
		(pad "2" smd custom
			(at 0 0.4445 90)
			(size 0.1397 0.1397)
			(layers "F.Cu" "F.Mask" "F.Paste")
			(net "P5V_B_4_MODE")
			(options
				(clearance outline)
				(anchor circle)
			)
			(primitives
				(gr_poly
					(pts
						(arc
							(start -0.1778 -0.2794)
							(mid -0.249642 -0.249642)
							(end -0.2794 -0.1778)
						)
						(arc
							(start -0.2794 0.1778)
							(mid -0.249642 0.249642)
							(end -0.1778 0.2794)
						)
						(arc
							(start 0.1778 0.2794)
							(mid 0.249642 0.249642)
							(end 0.2794 0.1778)
						)
						(arc
							(start 0.2794 -0.1778)
							(mid 0.249642 -0.249642)
							(end 0.1778 -0.2794)
						)
					)
					(width 0)
					(fill yes)
				)
			)
		)
	)
	(footprint ""
		(layer "F.Cu")
		(at 37.76853 -361.4928 90)
		(property "Reference" "U2"
			(at 0 0 90)
			(layer "F.SilkS")
			(hide yes)
			(effects
				(font
					(size 1.27 1.27)
				)
			)
		)
		(property "Value" "74LVC1G32DC-1GP"
			(at -2.3368 -8.6868 90)
			(unlocked yes)
			(layer "F.Fab")
			(hide yes)
			(effects
				(font
					(size 1.016 1.016)
					(thickness 0.1524)
				)
			)
		)
		(property "Device Type" "SC70-5H44"
			(at -2.3114 -10.414 90)
			(unlocked yes)
			(layer "F.Fab")
			(hide yes)
			(effects
				(font
					(size 1.016 1.016)
					(thickness 0.1524)
				)
			)
		)
		(duplicate_pad_numbers_are_jumpers no)
		(fp_line
			(start 1.3843 -1.8034)
			(end 1.3843 -1.1176)
			(stroke
				(width 0.3302)
				(type default)
			)
			(layer "F.SilkS")
		)
		(fp_line
			(start 0.6604 -1.8034)
			(end 1.3843 -1.8034)
			(stroke
				(width 0.3302)
				(type default)
			)
			(layer "F.SilkS")
		)
		(fp_line
			(start 1.27 -1.7018)
			(end 1.27 1.7018)
			(stroke
				(width 0.1524)
				(type default)
			)
			(layer "F.SilkS")
		)
		(fp_line
			(start -1.27 -1.7018)
			(end 1.27 -1.7018)
			(stroke
				(width 0.1524)
				(type default)
			)
			(layer "F.SilkS")
		)
		(fp_line
			(start 1.27 1.7018)
			(end -1.27 1.7018)
			(stroke
				(width 0.1524)
				(type default)
			)
			(layer "F.SilkS")
		)
		(fp_line
			(start -1.27 1.7018)
			(end -1.27 -1.7018)
			(stroke
				(width 0.1524)
				(type default)
			)
			(layer "F.SilkS")
		)
		(fp_rect
			(start -1.524 1.9558)
			(end 1.524 -1.9558)
			(stroke
				(width 0)
				(type default)
			)
			(fill no)
			(layer "F.CrtYd")
		)
		(fp_poly
			(pts
				(xy -1.524 -1.9558) (xy 1.524 -1.9558) (xy 1.524 1.9558) (xy -1.524 1.9558)
			)
			(stroke
				(width 0)
				(type default)
			)
			(fill no)
			(layer "F.Fab")
		)
		(pad "1" smd rect
			(at 0.65024 -0.8255 90)
			(size 0.4064 1.2192)
			(layers "F.Cu" "F.Mask" "F.Paste")
			(net "SCC_A_FULL_PWR_EN")
		)
		(pad "2" smd rect
			(at 0 -0.8255 90)
			(size 0.4064 1.2192)
			(layers "F.Cu" "F.Mask" "F.Paste")
			(net "SCC_B_FULL_PWR_EN")
		)
		(pad "3" smd rect
			(at -0.65024 -0.8255 90)
			(size 0.4064 1.2192)
			(layers "F.Cu" "F.Mask" "F.Paste")
			(net "GND")
		)
		(pad "4" smd rect
			(at -0.65024 0.8255 90)
			(size 0.4064 1.2192)
			(layers "F.Cu" "F.Mask" "F.Paste")
			(net "FAN_EN")
		)
		(pad "5" smd rect
			(at 0.65024 0.8255 90)
			(size 0.4064 1.2192)
			(layers "F.Cu" "F.Mask" "F.Paste")
			(net "P3V3_IN")
		)
	)
	(footprint ""
		(layer "F.Cu")
		(at 128.93548 -129.99085 90)
		(property "Reference" "VIA31"
			(at 0 0 90)
			(layer "F.SilkS")
			(hide yes)
			(effects
				(font
					(size 1.27 1.27)
				)
			)
		)
		(property "Value" "100OHM-8L-2D36MM-L18-GP"
			(at 3.8989 0.5715 90)
			(unlocked yes)
			(layer "F.Fab")
			(hide yes)
			(effects
				(font
					(size 1.016 1.016)
					(thickness 0.1524)
				)
			)
		)
		(property "Device Type" "VIA-PCIE-4P-414097"
			(at 3.8989 -0.9525 90)
			(unlocked yes)
			(layer "F.Fab")
			(hide yes)
			(effects
				(font
					(size 1.016 1.016)
					(thickness 0.1524)
				)
			)
		)
		(duplicate_pad_numbers_are_jumpers no)
		(fp_rect
			(start -2.0701 0.4826)
			(end 2.0701 -0.4826)
			(stroke
				(width 0)
				(type default)
			)
			(fill no)
			(layer "F.CrtYd")
		)
		(fp_rect
			(start -2.0701 0.4826)
			(end 2.0701 -0.4826)
			(stroke
				(width 0)
				(type default)
			)
			(fill no)
			(layer "F.Fab")
		)
		(pad "1" thru_hole circle
			(at -1.5875 0 90)
			(size 0.508 0.508)
			(drill 0.254)
			(layers "*.Cu" "*.Mask")
			(remove_unused_layers no)
			(net "GND")
			(clearance 0.2286)
			(thermal_gap 0.2286)
		)
		(pad "2" thru_hole circle
			(at -0.5715 0 90)
			(size 0.508 0.508)
			(drill 0.254)
			(layers "*.Cu" "*.Mask")
			(remove_unused_layers no)
			(net "PHY_SCC_B_TO_DRV_B_15_DP")
			(clearance 0.2286)
			(thermal_gap 0.2286)
		)
		(pad "3" thru_hole circle
			(at 0.5715 0 90)
			(size 0.508 0.508)
			(drill 0.254)
			(layers "*.Cu" "*.Mask")
			(remove_unused_layers no)
			(net "PHY_SCC_B_TO_DRV_B_15_DN")
			(clearance 0.2286)
			(thermal_gap 0.2286)
		)
		(pad "4" thru_hole circle
			(at 1.5875 0 90)
			(size 0.508 0.508)
			(drill 0.254)
			(layers "*.Cu" "*.Mask")
			(remove_unused_layers no)
			(net "GND")
			(clearance 0.2286)
			(thermal_gap 0.2286)
		)
	)
	(footprint ""
		(layer "F.Cu")
		(at 473.964 -35.56 90)
		(property "Reference" "R876"
			(at 0 0 90)
			(layer "F.SilkS")
			(hide yes)
			(effects
				(font
					(size 1.27 1.27)
				)
			)
		)
		(property "Value" "2R6F-GP"
			(at -0.0508 -4.8514 90)
			(unlocked yes)
			(layer "F.Fab")
			(hide yes)
			(effects
				(font
					(size 1.016 1.016)
					(thickness 0.1524)
				)
			)
		)
		(property "Device Type" "R1206H26"
			(at 0 -6.3754 90)
			(unlocked yes)
			(layer "F.Fab")
			(hide yes)
			(effects
				(font
					(size 1.016 1.016)
					(thickness 0.1524)
				)
			)
		)
		(duplicate_pad_numbers_are_jumpers no)
		(fp_line
			(start 1.016 -2.2352)
			(end 1.016 2.2352)
			(stroke
				(width 0.1524)
				(type default)
			)
			(layer "F.SilkS")
		)
		(fp_line
			(start -1.016 -2.2352)
			(end 1.016 -2.2352)
			(stroke
				(width 0.1524)
				(type default)
			)
			(layer "F.SilkS")
		)
		(fp_line
			(start 1.016 2.2352)
			(end -1.016 2.2352)
			(stroke
				(width 0.1524)
				(type default)
			)
			(layer "F.SilkS")
		)
		(fp_line
			(start -1.016 2.2352)
			(end -1.016 -2.2352)
			(stroke
				(width 0.1524)
				(type default)
			)
			(layer "F.SilkS")
		)
		(fp_rect
			(start -1.0922 2.3114)
			(end 1.0922 -2.3114)
			(stroke
				(width 0)
				(type default)
			)
			(fill no)
			(layer "F.CrtYd")
		)
		(fp_poly
			(pts
				(xy -1.0922 -2.3114) (xy 1.0922 -2.3114) (xy 1.0922 2.3114) (xy -1.0922 2.3114)
			)
			(stroke
				(width 0)
				(type default)
			)
			(fill no)
			(layer "F.Fab")
		)
		(pad "1" smd rect
			(at 0 -1.397 90)
			(size 1.651 1.27)
			(layers "F.Cu" "F.Mask" "F.Paste")
			(net "P12V_HDD35")
		)
		(pad "2" smd rect
			(at 0 1.397 90)
			(size 1.651 1.27)
			(layers "F.Cu" "F.Mask" "F.Paste")
			(net "12V_PRE_35")
		)
	)
	(footprint ""
		(layer "F.Cu")
		(at 172.847 -214.249)
		(property "Reference" "R284"
			(at 0 0 0)
			(layer "F.SilkS")
			(hide yes)
			(effects
				(font
					(size 1.27 1.27)
				)
			)
		)
		(property "Value" "130R3F-GP"
			(at -0.0254 -2.5146 0)
			(unlocked yes)
			(layer "F.Fab")
			(hide yes)
			(effects
				(font
					(size 1.016 1.016)
					(thickness 0.1524)
				)
			)
		)
		(property "Device Type" "R603H22"
			(at -0.0254 -4.0386 0)
			(unlocked yes)
			(layer "F.Fab")
			(hide yes)
			(effects
				(font
					(size 1.016 1.016)
					(thickness 0.1524)
				)
			)
		)
		(duplicate_pad_numbers_are_jumpers no)
		(fp_line
			(start -0.4826 0)
			(end -0.2032 0)
			(stroke
				(width 0.2032)
				(type default)
			)
			(layer "F.SilkS")
		)
		(fp_line
			(start 0.2032 0)
			(end 0.4826 0)
			(stroke
				(width 0.2032)
				(type default)
			)
			(layer "F.SilkS")
		)
		(fp_rect
			(start -0.5842 1.3335)
			(end 0.5842 -1.3335)
			(stroke
				(width 0)
				(type default)
			)
			(fill no)
			(layer "F.CrtYd")
		)
		(fp_rect
			(start -0.5842 1.3335)
			(end 0.5842 -1.3335)
			(stroke
				(width 0)
				(type default)
			)
			(fill no)
			(layer "F.Fab")
		)
		(pad "1" smd custom
			(at 0 -0.762)
			(size 0.2159 0.2159)
			(layers "F.Cu" "F.Mask" "F.Paste")
			(net "P5V_B_1")
			(options
				(clearance outline)
				(anchor circle)
			)
			(primitives
				(gr_poly
					(pts
						(arc
							(start -0.3302 -0.4318)
							(mid -0.402042 -0.402042)
							(end -0.4318 -0.3302)
						)
						(arc
							(start -0.4318 0.3302)
							(mid -0.402042 0.402042)
							(end -0.3302 0.4318)
						)
						(arc
							(start 0.3302 0.4318)
							(mid 0.402042 0.402042)
							(end 0.4318 0.3302)
						)
						(arc
							(start 0.4318 -0.3302)
							(mid 0.402042 -0.402042)
							(end 0.3302 -0.4318)
						)
					)
					(width 0)
					(fill yes)
				)
			)
		)
		(pad "2" smd custom
			(at 0 0.762)
			(size 0.2159 0.2159)
			(layers "F.Cu" "F.Mask" "F.Paste")
			(net "FLT_HDD5")
			(options
				(clearance outline)
				(anchor circle)
			)
			(primitives
				(gr_poly
					(pts
						(arc
							(start -0.3302 -0.4318)
							(mid -0.402042 -0.402042)
							(end -0.4318 -0.3302)
						)
						(arc
							(start -0.4318 0.3302)
							(mid -0.402042 0.402042)
							(end -0.3302 0.4318)
						)
						(arc
							(start 0.3302 0.4318)
							(mid 0.402042 0.402042)
							(end 0.4318 0.3302)
						)
						(arc
							(start 0.4318 -0.3302)
							(mid 0.402042 -0.402042)
							(end 0.3302 -0.4318)
						)
					)
					(width 0)
					(fill yes)
				)
			)
		)
	)
	(footprint ""
		(layer "F.Cu")
		(at 251.064522 -358.622346)
		(property "Reference" "R1044"
			(at 0 0 0)
			(layer "F.SilkS")
			(hide yes)
			(effects
				(font
					(size 1.27 1.27)
				)
			)
		)
		(property "Value" "75KR2F-GP"
			(at 0.064008 -3.993896 0)
			(unlocked yes)
			(layer "F.Fab")
			(hide yes)
			(effects
				(font
					(size 1.016 1.016)
					(thickness 0.1524)
				)
			)
		)
		(property "Device Type" "R402H16"
			(at 0.064008 -5.517896 0)
			(unlocked yes)
			(layer "F.Fab")
			(hide yes)
			(effects
				(font
					(size 1.016 1.016)
					(thickness 0.1524)
				)
			)
		)
		(duplicate_pad_numbers_are_jumpers no)
		(fp_line
			(start -0.508 -0.9398)
			(end -0.508 0.9398)
			(stroke
				(width 0.1524)
				(type default)
			)
			(layer "F.SilkS")
		)
		(fp_line
			(start 0.508 -0.9398)
			(end -0.508 -0.9398)
			(stroke
				(width 0.1524)
				(type default)
			)
			(layer "F.SilkS")
		)
		(fp_rect
			(start -0.508 0.9398)
			(end 0.508 -0.9398)
			(stroke
				(width 0)
				(type default)
			)
			(fill no)
			(layer "F.CrtYd")
		)
		(fp_rect
			(start -0.508 0.9398)
			(end 0.508 -0.9398)
			(stroke
				(width 0)
				(type default)
			)
			(fill no)
			(layer "F.Fab")
		)
		(pad "1" smd custom
			(at 0 -0.4445)
			(size 0.1397 0.1397)
			(layers "F.Cu" "F.Mask" "F.Paste")
			(net "MB3_ISET_R")
			(options
				(clearance outline)
				(anchor circle)
			)
			(primitives
				(gr_poly
					(pts
						(arc
							(start -0.1778 -0.2794)
							(mid -0.249642 -0.249642)
							(end -0.2794 -0.1778)
						)
						(arc
							(start -0.2794 0.1778)
							(mid -0.249642 0.249642)
							(end -0.1778 0.2794)
						)
						(arc
							(start 0.1778 0.2794)
							(mid 0.249642 0.249642)
							(end 0.2794 0.1778)
						)
						(arc
							(start 0.2794 -0.1778)
							(mid 0.249642 -0.249642)
							(end 0.1778 -0.2794)
						)
					)
					(width 0)
					(fill yes)
				)
			)
		)
		(pad "2" smd custom
			(at 0 0.4445)
			(size 0.1397 0.1397)
			(layers "F.Cu" "F.Mask" "F.Paste")
			(net "AGND_CURRENT_DPB")
			(options
				(clearance outline)
				(anchor circle)
			)
			(primitives
				(gr_poly
					(pts
						(arc
							(start -0.1778 -0.2794)
							(mid -0.249642 -0.249642)
							(end -0.2794 -0.1778)
						)
						(arc
							(start -0.2794 0.1778)
							(mid -0.249642 0.249642)
							(end -0.1778 0.2794)
						)
						(arc
							(start 0.1778 0.2794)
							(mid 0.249642 0.249642)
							(end 0.2794 0.1778)
						)
						(arc
							(start 0.2794 -0.1778)
							(mid 0.249642 -0.249642)
							(end 0.1778 -0.2794)
						)
					)
					(width 0)
					(fill yes)
				)
			)
		)
	)
	(footprint ""
		(layer "F.Cu")
		(at 329.278996 -369.697 180)
		(property "Reference" "R942"
			(at 0 0 180)
			(layer "F.SilkS")
			(hide yes)
			(effects
				(font
					(size 1.27 1.27)
				)
			)
		)
		(property "Value" "4K7R2F-GP"
			(at 0.064008 -3.993896 180)
			(unlocked yes)
			(layer "F.Fab")
			(hide yes)
			(effects
				(font
					(size 1.016 1.016)
					(thickness 0.1524)
				)
			)
		)
		(property "Device Type" "R402H16"
			(at 0.064008 -5.517896 180)
			(unlocked yes)
			(layer "F.Fab")
			(hide yes)
			(effects
				(font
					(size 1.016 1.016)
					(thickness 0.1524)
				)
			)
		)
		(duplicate_pad_numbers_are_jumpers no)
		(fp_line
			(start 0.508 -0.9398)
			(end -0.508 -0.9398)
			(stroke
				(width 0.1524)
				(type default)
			)
			(layer "F.SilkS")
		)
		(fp_line
			(start -0.508 -0.9398)
			(end -0.508 0.9398)
			(stroke
				(width 0.1524)
				(type default)
			)
			(layer "F.SilkS")
		)
		(fp_rect
			(start -0.508 0.9398)
			(end 0.508 -0.9398)
			(stroke
				(width 0)
				(type default)
			)
			(fill no)
			(layer "F.CrtYd")
		)
		(fp_rect
			(start -0.508 0.9398)
			(end 0.508 -0.9398)
			(stroke
				(width 0)
				(type default)
			)
			(fill no)
			(layer "F.Fab")
		)
		(pad "1" smd custom
			(at 0 -0.4445 180)
			(size 0.1397 0.1397)
			(layers "F.Cu" "F.Mask" "F.Paste")
			(net "P12V_IN")
			(options
				(clearance outline)
				(anchor circle)
			)
			(primitives
				(gr_poly
					(pts
						(arc
							(start -0.1778 -0.2794)
							(mid -0.249642 -0.249642)
							(end -0.2794 -0.1778)
						)
						(arc
							(start -0.2794 0.1778)
							(mid -0.249642 0.249642)
							(end -0.1778 0.2794)
						)
						(arc
							(start 0.1778 0.2794)
							(mid 0.249642 0.249642)
							(end 0.2794 0.1778)
						)
						(arc
							(start 0.2794 -0.1778)
							(mid 0.249642 -0.249642)
							(end 0.1778 -0.2794)
						)
					)
					(width 0)
					(fill yes)
				)
			)
		)
		(pad "2" smd custom
			(at 0 0.4445 180)
			(size 0.1397 0.1397)
			(layers "F.Cu" "F.Mask" "F.Paste")
			(net "FAN_2_TACH0")
			(options
				(clearance outline)
				(anchor circle)
			)
			(primitives
				(gr_poly
					(pts
						(arc
							(start -0.1778 -0.2794)
							(mid -0.249642 -0.249642)
							(end -0.2794 -0.1778)
						)
						(arc
							(start -0.2794 0.1778)
							(mid -0.249642 0.249642)
							(end -0.1778 0.2794)
						)
						(arc
							(start 0.1778 0.2794)
							(mid 0.249642 0.249642)
							(end 0.2794 0.1778)
						)
						(arc
							(start 0.2794 -0.1778)
							(mid 0.249642 -0.249642)
							(end 0.1778 -0.2794)
						)
					)
					(width 0)
					(fill yes)
				)
			)
		)
	)
)
